(kicad_pcb
	(version 20260206)
	(generator "pcbnew")
	(generator_version "10.0")
	(general
		(thickness 1.6)
		(legacy_teardrops no)
	)
	(paper "A4")
	(title_block
		(title "v2-pdb — ms_pdb_v2.brd")
		(comment 1 "Open CloudServer (Microsoft) / footprints 247-251 of 348")
	)
	(layers
		(0 "F.Cu" signal "TOP")
		(4 "In1.Cu" signal "GND")
		(6 "In2.Cu" signal "IN1")
		(8 "In3.Cu" signal "VCC")
		(10 "In4.Cu" signal "VCC1")
		(12 "In5.Cu" signal "IN2")
		(14 "In6.Cu" signal "GND1")
		(2 "B.Cu" signal "BOTTOM")
		(9 "F.Adhes" user "F.Adhesive")
		(11 "B.Adhes" user "B.Adhesive")
		(13 "F.Paste" user "Package Geometry/Pastemask Top")
		(15 "B.Paste" user "Package Geometry/Pastemask Bottom")
		(5 "F.SilkS" user "Ref Des/Silkscreen Top")
		(7 "B.SilkS" user "Ref Des/Silkscreen Bottom")
		(1 "F.Mask" user "Board Geometry/Soldermask Top")
		(3 "B.Mask" user "Board Geometry/Soldermask Bottom")
		(17 "Dwgs.User" user "User.Drawings")
		(19 "Cmts.User" user "User.Comments")
		(21 "Eco1.User" user "User.Eco1")
		(23 "Eco2.User" user "User.Eco2")
		(25 "Edge.Cuts" user "Board Geometry/Outline")
		(27 "Margin" user)
		(31 "F.CrtYd" user "Package Geometry/Place Bound Top")
		(29 "B.CrtYd" user "Package Geometry/Place Bound Bottom")
		(35 "F.Fab" user "Ref Des/Assembly Top")
		(33 "B.Fab" user "Ref Des/Assembly Bottom")
	)
	(footprint ""
		(layer "F.Cu")
		(at 77.999844 -32.29991)
		(property "Reference" "H12"
			(at 7.02183 -4.748784 0)
			(unlocked yes)
			(layer "F.SilkS")
			(effects
				(font
					(size 0.7874 0.5842)
					(thickness 0.1524)
				)
				(justify left)
			)
		)
		(property "Value" ""
			(at 0 0 0)
			(layer "F.Fab")
			(effects
				(font
					(size 1.27 1.27)
				)
			)
		)
		(duplicate_pad_numbers_are_jumpers no)
		(fp_circle
			(center 0 0)
			(end 7.999984 0)
			(stroke
				(width 0.1524)
				(type default)
			)
			(fill no)
			(layer "F.SilkS")
		)
		(fp_circle
			(center 0 0)
			(end 14.7066 0)
			(stroke
				(width 0.1524)
				(type default)
			)
			(fill no)
			(layer "B.SilkS")
		)
		(fp_poly
			(pts
				(arc
					(start 5.0038 0)
					(mid -5.0038 0)
					(end 5.0038 0)
				)
			)
			(stroke
				(width 0)
				(type default)
			)
			(fill no)
			(layer "F.CrtYd")
		)
		(pad "" np_thru_hole circle
			(at 0 0)
			(size 4.0132 4.0132)
			(drill 4.0132)
			(layers "*.Cu" "*.Mask")
			(clearance 0.381)
			(thermal_gap 0.381)
		)
		(pad "2" thru_hole circle
			(at 0 -3.50012)
			(size 0.762 0.762)
			(drill 0.5588)
			(layers "*.Cu" "*.Mask")
			(remove_unused_layers no)
			(net "GND")
			(clearance 0.1524)
			(thermal_gap 0.1524)
		)
		(pad "3" thru_hole circle
			(at -2.500122 -2.500122)
			(size 0.762 0.762)
			(drill 0.5588)
			(layers "*.Cu" "*.Mask")
			(remove_unused_layers no)
			(net "GND")
			(clearance 0.1524)
			(thermal_gap 0.1524)
		)
		(pad "4" thru_hole circle
			(at -3.50012 0)
			(size 0.762 0.762)
			(drill 0.5588)
			(layers "*.Cu" "*.Mask")
			(remove_unused_layers no)
			(net "GND")
			(clearance 0.1524)
			(thermal_gap 0.1524)
		)
		(pad "5" thru_hole circle
			(at -2.500122 2.500122)
			(size 0.762 0.762)
			(drill 0.5588)
			(layers "*.Cu" "*.Mask")
			(remove_unused_layers no)
			(net "GND")
			(clearance 0.1524)
			(thermal_gap 0.1524)
		)
		(pad "6" thru_hole circle
			(at 0 3.50012)
			(size 0.762 0.762)
			(drill 0.5588)
			(layers "*.Cu" "*.Mask")
			(remove_unused_layers no)
			(net "GND")
			(clearance 0.1524)
			(thermal_gap 0.1524)
		)
		(pad "7" thru_hole circle
			(at 2.500122 2.500122)
			(size 0.762 0.762)
			(drill 0.5588)
			(layers "*.Cu" "*.Mask")
			(remove_unused_layers no)
			(net "GND")
			(clearance 0.1524)
			(thermal_gap 0.1524)
		)
		(pad "8" thru_hole circle
			(at 3.50012 0)
			(size 0.762 0.762)
			(drill 0.5588)
			(layers "*.Cu" "*.Mask")
			(remove_unused_layers no)
			(net "GND")
			(clearance 0.1524)
			(thermal_gap 0.1524)
		)
		(pad "9" thru_hole circle
			(at 2.500122 -2.500122)
			(size 0.762 0.762)
			(drill 0.5588)
			(layers "*.Cu" "*.Mask")
			(remove_unused_layers no)
			(net "GND")
			(clearance 0.1524)
			(thermal_gap 0.1524)
		)
		(zone
			(layer "F.Cu")
			(hatch none 0.5)
			(connect_pads
				(clearance 0)
			)
			(min_thickness 0.25)
			(keepout
				(tracks not_allowed)
				(vias allowed)
				(pads allowed)
				(copperpour not_allowed)
				(footprints allowed)
			)
			(placement
				(enabled no)
				(sheetname "")
			)
			(fill
				(thermal_gap 0.5)
				(thermal_bridge_width 0.5)
				(island_removal_mode 0)
			)
			(polygon
				(pts
					(arc
						(start 77.999844 -40.30091)
						(mid 69.998844 -32.29991)
						(end 77.999844 -24.29891)
					)
					(arc
						(start 77.999844 -24.29891)
						(mid 79.434944 -25.73401)
						(end 77.999844 -27.16911)
					)
					(arc
						(start 77.999844 -27.16911)
						(mid 72.869044 -32.29991)
						(end 77.999844 -37.43071)
					)
					(arc
						(start 77.999844 -37.43071)
						(mid 79.434944 -38.86581)
						(end 77.999844 -40.30091)
					)
				)
			)
		)
		(zone
			(layer "F.Cu")
			(hatch none 0.5)
			(connect_pads
				(clearance 0)
			)
			(min_thickness 0.25)
			(keepout
				(tracks not_allowed)
				(vias allowed)
				(pads allowed)
				(copperpour not_allowed)
				(footprints allowed)
			)
			(placement
				(enabled no)
				(sheetname "")
			)
			(fill
				(thermal_gap 0.5)
				(thermal_bridge_width 0.5)
				(island_removal_mode 0)
			)
			(polygon
				(pts
					(arc
						(start 77.999844 -40.30091)
						(mid 86.000844 -32.29991)
						(end 77.999844 -24.29891)
					)
					(arc
						(start 77.999844 -24.29891)
						(mid 76.564744 -25.73401)
						(end 77.999844 -27.16911)
					)
					(arc
						(start 77.999844 -27.16911)
						(mid 83.130644 -32.29991)
						(end 77.999844 -37.43071)
					)
					(arc
						(start 77.999844 -37.43071)
						(mid 76.564744 -38.86581)
						(end 77.999844 -40.30091)
					)
				)
			)
		)
		(zone
			(layers "F.Cu" "B.Cu" "In1.Cu" "In2.Cu" "In3.Cu" "In4.Cu" "In5.Cu" "In6.Cu")
			(hatch none 0.5)
			(connect_pads
				(clearance 0)
			)
			(min_thickness 0.25)
			(keepout
				(tracks not_allowed)
				(vias allowed)
				(pads allowed)
				(copperpour not_allowed)
				(footprints allowed)
			)
			(placement
				(enabled no)
				(sheetname "")
			)
			(fill
				(thermal_gap 0.5)
				(thermal_bridge_width 0.5)
				(island_removal_mode 0)
			)
			(polygon
				(pts
					(arc
						(start 80.511904 -32.29991)
						(mid 75.487784 -32.29991)
						(end 80.511904 -32.29991)
					)
				)
			)
		)
	)
	(footprint ""
		(layer "F.Cu")
		(at 13.438124 -322.972176 180)
		(property "Reference" "R147"
			(at -1.656842 -0.102362 0)
			(unlocked yes)
			(layer "F.SilkS")
			(effects
				(font
					(size 0.7874 0.5842)
					(thickness 0.1524)
				)
				(justify left)
			)
		)
		(property "Value" ""
			(at 0 0 180)
			(layer "F.Fab")
			(effects
				(font
					(size 1.27 1.27)
				)
			)
		)
		(duplicate_pad_numbers_are_jumpers no)
		(fp_line
			(start 0.7874 0.4064)
			(end -0.7874 0.4064)
			(stroke
				(width 0.1524)
				(type default)
			)
			(layer "F.SilkS")
		)
		(fp_line
			(start 0.7874 -0.4064)
			(end 0.7874 0.4064)
			(stroke
				(width 0.1524)
				(type default)
			)
			(layer "F.SilkS")
		)
		(fp_line
			(start -0.7874 0.4064)
			(end -0.7874 -0.4064)
			(stroke
				(width 0.1524)
				(type default)
			)
			(layer "F.SilkS")
		)
		(fp_line
			(start -0.7874 -0.4064)
			(end 0.7874 -0.4064)
			(stroke
				(width 0.1524)
				(type default)
			)
			(layer "F.SilkS")
		)
		(fp_poly
			(pts
				(xy -0.508 0.2794) (xy -0.508 0.2286) (xy -0.635 0.2286) (xy -0.635 -0.254) (xy -0.5334 -0.254)
				(xy -0.5334 -0.2794) (xy 0.5334 -0.2794) (xy 0.5334 -0.254) (xy 0.635 -0.254) (xy 0.635 0.254) (xy 0.5334 0.254)
				(xy 0.5334 0.2794)
			)
			(stroke
				(width 0)
				(type default)
			)
			(fill no)
			(layer "F.CrtYd")
		)
		(pad "1" smd rect
			(at 0.40005 0 180)
			(size 0.4572 0.508)
			(layers "F.Cu" "F.Mask" "F.Paste")
			(net "FAN6_TACH")
		)
		(pad "2" smd rect
			(at -0.40005 0 180)
			(size 0.4572 0.508)
			(layers "F.Cu" "F.Mask" "F.Paste")
			(net "P12V")
		)
	)
	(footprint ""
		(layer "F.Cu")
		(at 97.946464 -505.85878)
		(property "Reference" ""
			(at 0 0 0)
			(layer "F.SilkS")
			(hide yes)
			(effects
				(font
					(size 1.27 1.27)
				)
			)
		)
		(property "Value" ""
			(at 0 0 0)
			(layer "F.Fab")
			(effects
				(font
					(size 1.27 1.27)
				)
			)
		)
		(duplicate_pad_numbers_are_jumpers no)
		(fp_poly
			(pts
				(arc
					(start 1.4986 0)
					(mid -1.4986 0)
					(end 1.4986 0)
				)
			)
			(stroke
				(width 0)
				(type default)
			)
			(fill no)
			(layer "F.CrtYd")
		)
		(pad "1" smd circle
			(at 0 0)
			(size 0.9906 0.9906)
			(layers "F.Cu" "F.Mask" "F.Paste")
			(net "Net_222")
		)
		(zone
			(layer "F.Cu")
			(hatch none 0.5)
			(connect_pads
				(clearance 0)
			)
			(min_thickness 0.25)
			(keepout
				(tracks not_allowed)
				(vias allowed)
				(pads allowed)
				(copperpour not_allowed)
				(footprints allowed)
			)
			(placement
				(enabled no)
				(sheetname "")
			)
			(fill
				(thermal_gap 0.5)
				(thermal_bridge_width 0.5)
				(island_removal_mode 0)
			)
			(polygon
				(pts
					(arc
						(start 99.572064 -505.85878)
						(mid 96.320864 -505.85878)
						(end 99.572064 -505.85878)
					)
				)
			)
		)
	)
	(footprint ""
		(layer "F.Cu")
		(at 13.964666 -52.451 -90)
		(property "Reference" "J21"
			(at -4.421378 5.357368 0)
			(unlocked yes)
			(layer "F.SilkS")
			(effects
				(font
					(size 0.7874 0.5842)
					(thickness 0.1524)
				)
				(justify left)
			)
		)
		(property "Value" ""
			(at 0 0 270)
			(layer "F.Fab")
			(effects
				(font
					(size 1.27 1.27)
				)
			)
		)
		(duplicate_pad_numbers_are_jumpers no)
		(fp_line
			(start -3.370072 12.830048)
			(end -3.370072 -3.81)
			(stroke
				(width 0.1524)
				(type default)
			)
			(layer "F.SilkS")
		)
		(fp_line
			(start 12.260072 12.830048)
			(end -3.370072 12.830048)
			(stroke
				(width 0.1524)
				(type default)
			)
			(layer "F.SilkS")
		)
		(fp_line
			(start -3.370072 -3.81)
			(end 12.260072 -3.81)
			(stroke
				(width 0.1524)
				(type default)
			)
			(layer "F.SilkS")
		)
		(fp_line
			(start 12.260072 -3.81)
			(end 12.260072 12.830048)
			(stroke
				(width 0.1524)
				(type default)
			)
			(layer "F.SilkS")
		)
		(fp_poly
			(pts
				(xy -3.576828 0) (xy -5.0038 0.713486) (xy -5.0038 -0.713486)
			)
			(stroke
				(width 0)
				(type default)
			)
			(fill yes)
			(layer "F.SilkS")
		)
		(fp_poly
			(pts
				(xy -0.762 0.762) (xy 8.382 0.762) (xy 8.382 -1.8034) (xy 9.652 -1.8034) (xy 9.652 -3.302) (xy 0.508 -3.302)
				(xy 0.508 -0.762) (xy -0.762 -0.762)
			)
			(stroke
				(width 0)
				(type default)
			)
			(fill no)
			(layer "B.CrtYd")
		)
		(fp_poly
			(pts
				(arc
					(start -1.27 4.4196)
					(mid -1.27 8.2804)
					(end -1.27 4.4196)
				)
			)
			(stroke
				(width 0)
				(type default)
			)
			(fill no)
			(layer "B.CrtYd")
		)
		(fp_poly
			(pts
				(arc
					(start 10.16 4.4196)
					(mid 10.16 8.2804)
					(end 10.16 4.4196)
				)
			)
			(stroke
				(width 0)
				(type default)
			)
			(fill no)
			(layer "B.CrtYd")
		)
		(fp_poly
			(pts
				(xy -3.370072 12.830048) (xy 12.260072 12.830048) (xy 12.260072 -3.81) (xy -3.370072 -3.81)
			)
			(stroke
				(width 0)
				(type default)
			)
			(fill no)
			(layer "F.CrtYd")
		)
		(fp_line
			(start -3.370072 12.830048)
			(end -3.370072 -3.81)
			(stroke
				(width 0.1)
				(type default)
			)
			(layer "F.Fab")
		)
		(fp_line
			(start 12.260072 12.830048)
			(end -3.370072 12.830048)
			(stroke
				(width 0.1)
				(type default)
			)
			(layer "F.Fab")
		)
		(fp_line
			(start -3.370072 -3.81)
			(end 12.260072 -3.81)
			(stroke
				(width 0.1)
				(type default)
			)
			(layer "F.Fab")
		)
		(fp_line
			(start 12.260072 -3.81)
			(end 12.260072 12.830048)
			(stroke
				(width 0.1)
				(type default)
			)
			(layer "F.Fab")
		)
		(fp_poly
			(pts
				(xy -3.576828 0) (xy -5.0038 0.713486) (xy -5.0038 -0.713486)
			)
			(stroke
				(width 0)
				(type default)
			)
			(fill yes)
			(layer "F.Fab")
		)
		(fp_text user "7"
			(at 13.08989 0.05461 0)
			(unlocked yes)
			(layer "F.SilkS")
			(effects
				(font
					(size 0.7874 0.5842)
					(thickness 0.1524)
				)
			)
		)
		(fp_text user "1"
			(at -4.066286 -1.113536 0)
			(unlocked yes)
			(layer "F.SilkS")
			(effects
				(font
					(size 0.7874 0.5842)
					(thickness 0.1524)
				)
			)
		)
		(fp_text user "8"
			(at 12.91463 -2.608834 0)
			(unlocked yes)
			(layer "F.SilkS")
			(effects
				(font
					(size 0.7874 0.5842)
					(thickness 0.1524)
				)
			)
		)
		(fp_text user "2"
			(at -4.101592 -2.863342 0)
			(unlocked yes)
			(layer "F.SilkS")
			(effects
				(font
					(size 0.7874 0.5842)
					(thickness 0.1524)
				)
			)
		)
		(fp_text user "1"
			(at -1.344676 0.284734 0)
			(unlocked yes)
			(layer "B.SilkS")
			(effects
				(font
					(size 0.7874 0.5842)
					(thickness 0.1524)
				)
				(justify mirror)
			)
		)
		(fp_text user "7"
			(at 9.505696 0.062484 0)
			(unlocked yes)
			(layer "B.SilkS")
			(effects
				(font
					(size 0.7874 0.5842)
					(thickness 0.1524)
				)
				(justify mirror)
			)
		)
		(fp_text user "2"
			(at -0.049276 -2.382266 0)
			(unlocked yes)
			(layer "B.SilkS")
			(effects
				(font
					(size 0.7874 0.5842)
					(thickness 0.1524)
				)
				(justify mirror)
			)
		)
		(fp_text user "8"
			(at 10.274808 -2.563368 0)
			(unlocked yes)
			(layer "B.SilkS")
			(effects
				(font
					(size 0.7874 0.5842)
					(thickness 0.1524)
				)
				(justify mirror)
			)
		)
		(fp_text user "7"
			(at 8.8138 0.238252 270)
			(unlocked yes)
			(layer "B.Fab")
			(effects
				(font
					(size 0.7874 0.5842)
					(thickness 0.000001)
				)
				(justify mirror)
			)
		)
		(fp_text user "1"
			(at -1.2954 0.085852 270)
			(unlocked yes)
			(layer "B.Fab")
			(effects
				(font
					(size 0.7874 0.5842)
					(thickness 0.000001)
				)
				(justify mirror)
			)
		)
		(fp_text user "8"
			(at 10.0838 -2.403348 270)
			(unlocked yes)
			(layer "B.Fab")
			(effects
				(font
					(size 0.7874 0.5842)
					(thickness 0.000001)
				)
				(justify mirror)
			)
		)
		(fp_text user "2"
			(at 0 -2.581148 270)
			(unlocked yes)
			(layer "B.Fab")
			(effects
				(font
					(size 0.7874 0.5842)
					(thickness 0.000001)
				)
				(justify mirror)
			)
		)
		(fp_text user "7"
			(at 12.7762 -0.091948 270)
			(unlocked yes)
			(layer "F.Fab")
			(effects
				(font
					(size 0.7874 0.5842)
					(thickness 0.000001)
				)
			)
		)
		(fp_text user "1"
			(at -3.9116 -0.930148 270)
			(unlocked yes)
			(layer "F.Fab")
			(effects
				(font
					(size 0.7874 0.5842)
					(thickness 0.000001)
				)
			)
		)
		(fp_text user "2"
			(at -3.9624 -2.428748 270)
			(unlocked yes)
			(layer "F.Fab")
			(effects
				(font
					(size 0.7874 0.5842)
					(thickness 0.000001)
				)
			)
		)
		(fp_text user "8"
			(at 12.7762 -2.555748 270)
			(unlocked yes)
			(layer "F.Fab")
			(effects
				(font
					(size 0.7874 0.5842)
					(thickness 0.000001)
				)
			)
		)
		(pad "" np_thru_hole circle
			(at -1.27 6.35 270)
			(size 3.3528 3.3528)
			(drill 3.3528)
			(layers "*.Cu" "*.Mask")
			(clearance 0.381)
			(thermal_gap 0.381)
		)
		(pad "" np_thru_hole circle
			(at 10.16 6.35 270)
			(size 3.3528 3.3528)
			(drill 3.3528)
			(layers "*.Cu" "*.Mask")
			(clearance 0.381)
			(thermal_gap 0.381)
		)
		(pad "1" thru_hole rect
			(at 0 0 270)
			(size 1.397 1.397)
			(drill 0.9906)
			(layers "*.Cu" "*.Mask")
			(remove_unused_layers no)
			(net "UART_RTS_P2_L_N")
			(clearance 0.0508)
			(thermal_gap 0.0508)
			(padstack
				(mode front_inner_back)
				(layer "Inner"
					(shape circle)
					(size 1.397 1.397)
					(clearance 0.0508)
				)
				(layer "B.Cu"
					(shape rect)
					(size 1.397 1.397)
					(clearance 0.0508)
				)
			)
		)
		(pad "2" thru_hole circle
			(at 1.27 -2.54 270)
			(size 1.397 1.397)
			(drill 0.9906)
			(layers "*.Cu" "*.Mask")
			(remove_unused_layers no)
			(net "UART_DSR_P2_L_N")
			(clearance 0.0508)
			(thermal_gap 0.0508)
		)
		(pad "3" thru_hole circle
			(at 2.54 0 270)
			(size 1.397 1.397)
			(drill 0.9906)
			(layers "*.Cu" "*.Mask")
			(remove_unused_layers no)
			(net "UART_RX_P2_L")
			(clearance 0.0508)
			(thermal_gap 0.0508)
		)
		(pad "4" thru_hole circle
			(at 3.81 -2.54 270)
			(size 1.397 1.397)
			(drill 0.9906)
			(layers "*.Cu" "*.Mask")
			(remove_unused_layers no)
			(net "GND")
			(clearance 0.0508)
			(thermal_gap 0.0508)
		)
		(pad "5" thru_hole circle
			(at 5.08 0 270)
			(size 1.397 1.397)
			(drill 0.9906)
			(layers "*.Cu" "*.Mask")
			(remove_unused_layers no)
			(net "GND")
			(clearance 0.0508)
			(thermal_gap 0.0508)
		)
		(pad "6" thru_hole circle
			(at 6.35 -2.54 270)
			(size 1.397 1.397)
			(drill 0.9906)
			(layers "*.Cu" "*.Mask")
			(remove_unused_layers no)
			(net "UART_TX_P2_L")
			(clearance 0.0508)
			(thermal_gap 0.0508)
		)
		(pad "7" thru_hole circle
			(at 7.62 0 270)
			(size 1.397 1.397)
			(drill 0.9906)
			(layers "*.Cu" "*.Mask")
			(remove_unused_layers no)
			(net "UART_DTR_P2_L_N")
			(clearance 0.0508)
			(thermal_gap 0.0508)
		)
		(pad "8" thru_hole circle
			(at 8.89 -2.54 270)
			(size 1.397 1.397)
			(drill 0.9906)
			(layers "*.Cu" "*.Mask")
			(remove_unused_layers no)
			(net "UART_CTS_P2_L_N")
			(clearance 0.0508)
			(thermal_gap 0.0508)
		)
		(zone
			(layers "F.Cu" "B.Cu" "In1.Cu" "In2.Cu" "In3.Cu" "In4.Cu" "In5.Cu" "In6.Cu")
			(hatch none 0.5)
			(connect_pads
				(clearance 0)
			)
			(min_thickness 0.25)
			(keepout
				(tracks not_allowed)
				(vias allowed)
				(pads allowed)
				(copperpour not_allowed)
				(footprints allowed)
			)
			(placement
				(enabled no)
				(sheetname "")
			)
			(fill
				(thermal_gap 0.5)
				(thermal_bridge_width 0.5)
				(island_removal_mode 0)
			)
			(polygon
				(pts
					(arc
						(start 9.697466 -53.721)
						(mid 5.531866 -53.721)
						(end 9.697466 -53.721)
					)
				)
			)
		)
		(zone
			(layers "F.Cu" "B.Cu" "In1.Cu" "In2.Cu" "In3.Cu" "In4.Cu" "In5.Cu" "In6.Cu")
			(hatch none 0.5)
			(connect_pads
				(clearance 0)
			)
			(min_thickness 0.25)
			(keepout
				(tracks not_allowed)
				(vias allowed)
				(pads allowed)
				(copperpour not_allowed)
				(footprints allowed)
			)
			(placement
				(enabled no)
				(sheetname "")
			)
			(fill
				(thermal_gap 0.5)
				(thermal_bridge_width 0.5)
				(island_removal_mode 0)
			)
			(polygon
				(pts
					(arc
						(start 9.697466 -42.291)
						(mid 5.531866 -42.291)
						(end 9.697466 -42.291)
					)
				)
			)
		)
	)
	(footprint ""
		(layer "F.Cu")
		(at 46.496478 -248.705116 180)
		(property "Reference" "R95"
			(at -0.92964 -0.866902 0)
			(unlocked yes)
			(layer "F.SilkS")
			(effects
				(font
					(size 0.7874 0.5842)
					(thickness 0.1524)
				)
				(justify left)
			)
		)
		(property "Value" ""
			(at 0 0 180)
			(layer "F.Fab")
			(effects
				(font
					(size 1.27 1.27)
				)
			)
		)
		(duplicate_pad_numbers_are_jumpers no)
		(fp_line
			(start 0.7874 0.4064)
			(end -0.7874 0.4064)
			(stroke
				(width 0.1524)
				(type default)
			)
			(layer "F.SilkS")
		)
		(fp_line
			(start 0.7874 -0.4064)
			(end 0.7874 0.4064)
			(stroke
				(width 0.1524)
				(type default)
			)
			(layer "F.SilkS")
		)
		(fp_line
			(start -0.7874 0.4064)
			(end -0.7874 -0.4064)
			(stroke
				(width 0.1524)
				(type default)
			)
			(layer "F.SilkS")
		)
		(fp_line
			(start -0.7874 -0.4064)
			(end 0.7874 -0.4064)
			(stroke
				(width 0.1524)
				(type default)
			)
			(layer "F.SilkS")
		)
		(fp_poly
			(pts
				(xy -0.508 0.2794) (xy -0.508 0.2286) (xy -0.635 0.2286) (xy -0.635 -0.254) (xy -0.5334 -0.254)
				(xy -0.5334 -0.2794) (xy 0.5334 -0.2794) (xy 0.5334 -0.254) (xy 0.635 -0.254) (xy 0.635 0.254) (xy 0.5334 0.254)
				(xy 0.5334 0.2794)
			)
			(stroke
				(width 0)
				(type default)
			)
			(fill no)
			(layer "F.CrtYd")
		)
		(pad "1" smd rect
			(at 0.40005 0 180)
			(size 0.4572 0.508)
			(layers "F.Cu" "F.Mask" "F.Paste")
			(net "PSU3_REMOTE_R_N")
		)
		(pad "2" smd rect
			(at -0.40005 0 180)
			(size 0.4572 0.508)
			(layers "F.Cu" "F.Mask" "F.Paste")
			(net "GND")
		)
	)
)
